(kicad_pcb
	(version 20260206)
	(generator "pcbnew")
	(generator_version "10.0")
	(general
		(thickness 1.6)
		(legacy_teardrops no)
	)
	(paper "A4")
	(title_block
		(title "v1-tray-backplane — T6M_tray_BP_c_1023_1120.brd")
		(comment 1 "Open CloudServer (Microsoft) / footprints 64-70 of 170")
	)
	(layers
		(0 "F.Cu" signal "TOP")
		(4 "In1.Cu" signal "GND")
		(6 "In2.Cu" signal "IN1")
		(8 "In3.Cu" signal "VCC")
		(10 "In4.Cu" signal "VCC1")
		(12 "In5.Cu" signal "IN2")
		(14 "In6.Cu" signal "GND1")
		(2 "B.Cu" signal "BOTTOM")
		(9 "F.Adhes" user "F.Adhesive")
		(11 "B.Adhes" user "B.Adhesive")
		(13 "F.Paste" user "Package Geometry/Pastemask Top")
		(15 "B.Paste" user "Package Geometry/Pastemask Bottom")
		(5 "F.SilkS" user "Ref Des/Silkscreen Top")
		(7 "B.SilkS" user "Ref Des/Silkscreen Bottom")
		(1 "F.Mask" user "Board Geometry/Soldermask Top")
		(3 "B.Mask" user "Board Geometry/Soldermask Bottom")
		(17 "Dwgs.User" user "User.Drawings")
		(19 "Cmts.User" user "User.Comments")
		(21 "Eco1.User" user "User.Eco1")
		(23 "Eco2.User" user "User.Eco2")
		(25 "Edge.Cuts" user "Board Geometry/Outline")
		(27 "Margin" user)
		(31 "F.CrtYd" user "Package Geometry/Place Bound Top")
		(29 "B.CrtYd" user "Package Geometry/Place Bound Bottom")
		(35 "F.Fab" user "Ref Des/Assembly Top")
		(33 "B.Fab" user "Ref Des/Assembly Bottom")
	)
	(footprint ""
		(layer "F.Cu")
		(at 300.810168 -41.500044 180)
		(property "Reference" "H6"
			(at -0.156464 -5.33654 0)
			(unlocked yes)
			(layer "F.SilkS")
			(effects
				(font
					(size 0.7874 0.5842)
					(thickness 0.1524)
				)
				(justify left)
			)
		)
		(property "Value" ""
			(at 0 0 180)
			(layer "F.Fab")
			(effects
				(font
					(size 1.27 1.27)
				)
			)
		)
		(duplicate_pad_numbers_are_jumpers no)
		(fp_poly
			(pts
				(arc
					(start 3.999992 5.999988)
					(mid 0 9.99998)
					(end -3.999992 5.999988)
				)
				(arc
					(start -3.999992 0)
					(mid 0 -3.999992)
					(end 3.999992 0)
				)
			)
			(stroke
				(width 0)
				(type default)
			)
			(fill no)
			(layer "B.CrtYd")
		)
		(fp_poly
			(pts
				(arc
					(start 3.999992 5.999988)
					(mid 0 9.99998)
					(end -3.999992 5.999988)
				)
				(arc
					(start -3.999992 0)
					(mid 0 -3.999992)
					(end 3.999992 0)
				)
			)
			(stroke
				(width 0)
				(type default)
			)
			(fill no)
			(layer "F.CrtYd")
		)
		(pad "" np_thru_hole circle
			(at 0 0 180)
			(size 3.5052 3.5052)
			(drill 3.5052)
			(layers "*.Cu" "*.Mask")
			(clearance 0.381)
			(thermal_gap 0.381)
		)
		(zone
			(layers "F.Cu" "B.Cu" "In1.Cu" "In2.Cu" "In3.Cu" "In4.Cu" "In5.Cu" "In6.Cu")
			(hatch none 0.5)
			(connect_pads
				(clearance 0)
			)
			(min_thickness 0.25)
			(keepout
				(tracks not_allowed)
				(vias allowed)
				(pads allowed)
				(copperpour not_allowed)
				(footprints allowed)
			)
			(placement
				(enabled no)
				(sheetname "")
			)
			(fill
				(thermal_gap 0.5)
				(thermal_bridge_width 0.5)
				(island_removal_mode 0)
			)
			(polygon
				(pts
					(arc
						(start 298.398438 -44.952666)
						(mid 300.810168 -51.007954)
						(end 303.221898 -44.952666)
					)
					(arc
						(start 303.221898 -44.952666)
						(mid 303.108269 -44.789805)
						(end 303.068228 -44.595288)
					)
					(arc
						(start 303.068228 -41.500044)
						(mid 300.810168 -39.241984)
						(end 298.552108 -41.500044)
					)
					(arc
						(start 298.552108 -44.595288)
						(mid 298.512122 -44.789828)
						(end 298.398438 -44.952666)
					)
				)
			)
		)
	)
	(footprint ""
		(layer "F.Cu")
		(at 351.177352 -22.159468)
		(property "Reference" "R70"
			(at -58.908696 -4.409948 0)
			(unlocked yes)
			(layer "F.SilkS")
			(effects
				(font
					(size 0.7874 0.5842)
					(thickness 0.1524)
				)
				(justify left)
			)
		)
		(property "Value" ""
			(at 0 0 0)
			(layer "F.Fab")
			(effects
				(font
					(size 1.27 1.27)
				)
			)
		)
		(duplicate_pad_numbers_are_jumpers no)
		(fp_line
			(start -0.7874 -0.4064)
			(end 0.7874 -0.4064)
			(stroke
				(width 0.1524)
				(type default)
			)
			(layer "F.SilkS")
		)
		(fp_line
			(start -0.7874 0.4064)
			(end -0.7874 -0.4064)
			(stroke
				(width 0.1524)
				(type default)
			)
			(layer "F.SilkS")
		)
		(fp_line
			(start 0.7874 -0.4064)
			(end 0.7874 0.4064)
			(stroke
				(width 0.1524)
				(type default)
			)
			(layer "F.SilkS")
		)
		(fp_line
			(start 0.7874 0.4064)
			(end -0.7874 0.4064)
			(stroke
				(width 0.1524)
				(type default)
			)
			(layer "F.SilkS")
		)
		(fp_poly
			(pts
				(xy -0.508 0.2794) (xy -0.508 0.2286) (xy -0.635 0.2286) (xy -0.635 -0.254) (xy -0.5334 -0.254)
				(xy -0.5334 -0.2794) (xy 0.5334 -0.2794) (xy 0.5334 -0.254) (xy 0.635 -0.254) (xy 0.635 0.254) (xy 0.5334 0.254)
				(xy 0.5334 0.2794)
			)
			(stroke
				(width 0)
				(type default)
			)
			(fill no)
			(layer "F.CrtYd")
		)
		(pad "1" smd rect
			(at 0.40005 0)
			(size 0.4572 0.508)
			(layers "F.Cu" "F.Mask" "F.Paste")
			(net "ENET10G_3_LOS")
		)
		(pad "2" smd rect
			(at -0.40005 0)
			(size 0.4572 0.508)
			(layers "F.Cu" "F.Mask" "F.Paste")
			(net "SFP3_PRESENT_N")
		)
	)
	(footprint ""
		(layer "F.Cu")
		(at 145.2118 -3.048 90)
		(property "Reference" "C18"
			(at -2.2606 -8.194548 90)
			(unlocked yes)
			(layer "F.SilkS")
			(effects
				(font
					(size 0.7874 0.5842)
					(thickness 0.1524)
				)
				(justify left)
			)
		)
		(property "Value" ""
			(at 0 0 90)
			(layer "F.Fab")
			(effects
				(font
					(size 1.27 1.27)
				)
			)
		)
		(duplicate_pad_numbers_are_jumpers no)
		(fp_line
			(start 0.7874 -0.4064)
			(end 0.7874 0.4064)
			(stroke
				(width 0.1524)
				(type default)
			)
			(layer "F.SilkS")
		)
		(fp_line
			(start -0.7874 -0.4064)
			(end 0.7874 -0.4064)
			(stroke
				(width 0.1524)
				(type default)
			)
			(layer "F.SilkS")
		)
		(fp_line
			(start 0 0.381)
			(end 0 -0.381)
			(stroke
				(width 0.1524)
				(type default)
			)
			(layer "F.SilkS")
		)
		(fp_line
			(start 0.7874 0.4064)
			(end -0.7874 0.4064)
			(stroke
				(width 0.1524)
				(type default)
			)
			(layer "F.SilkS")
		)
		(fp_line
			(start -0.7874 0.4064)
			(end -0.7874 -0.4064)
			(stroke
				(width 0.1524)
				(type default)
			)
			(layer "F.SilkS")
		)
		(fp_poly
			(pts
				(xy -0.5334 0.254) (xy -0.635 0.254) (xy -0.635 0.2286) (xy -0.635 -0.254) (xy -0.5334 -0.254) (xy -0.5334 -0.2794)
				(xy 0.5334 -0.2794) (xy 0.5334 -0.254) (xy 0.635 -0.254) (xy 0.635 0.254) (xy 0.5334 0.254) (xy 0.5334 0.2794)
				(xy -0.508 0.2794) (xy -0.5334 0.2794)
			)
			(stroke
				(width 0)
				(type default)
			)
			(fill no)
			(layer "F.CrtYd")
		)
		(pad "1" smd rect
			(at 0.40005 0 90)
			(size 0.4572 0.508)
			(layers "F.Cu" "F.Mask" "F.Paste")
			(net "P3V3_10G_1_VCCT")
		)
		(pad "2" smd rect
			(at -0.40005 0 90)
			(size 0.4572 0.508)
			(layers "F.Cu" "F.Mask" "F.Paste")
			(net "GND")
		)
	)
	(footprint ""
		(layer "F.Cu")
		(at 29.029152 -23.484332 180)
		(property "Reference" "JP7"
			(at 0.527304 -1.935734 0)
			(unlocked yes)
			(layer "F.SilkS")
			(effects
				(font
					(size 0.7874 0.5842)
					(thickness 0.1524)
				)
				(justify left)
			)
		)
		(property "Value" ""
			(at 0 0 180)
			(layer "F.Fab")
			(effects
				(font
					(size 1.27 1.27)
				)
			)
		)
		(duplicate_pad_numbers_are_jumpers no)
		(fp_line
			(start 2.54 1.27)
			(end -2.54 1.27)
			(stroke
				(width 0.1524)
				(type default)
			)
			(layer "F.SilkS")
		)
		(fp_line
			(start 2.54 -1.27)
			(end 2.54 1.27)
			(stroke
				(width 0.1524)
				(type default)
			)
			(layer "F.SilkS")
		)
		(fp_line
			(start -2.54 1.27)
			(end -2.54 -1.27)
			(stroke
				(width 0.1524)
				(type default)
			)
			(layer "F.SilkS")
		)
		(fp_line
			(start -2.54 -1.27)
			(end 2.54 -1.27)
			(stroke
				(width 0.1524)
				(type default)
			)
			(layer "F.SilkS")
		)
		(fp_poly
			(pts
				(xy -2.71018 0.089916) (xy -4.03098 -0.494284) (xy -4.03098 0.724916)
			)
			(stroke
				(width 0)
				(type default)
			)
			(fill yes)
			(layer "F.SilkS")
		)
		(fp_poly
			(pts
				(xy -2.1082 -0.8382) (xy -2.1082 0.8382) (xy 2.1082 0.8382) (xy 2.1082 -0.8382)
			)
			(stroke
				(width 0)
				(type default)
			)
			(fill no)
			(layer "B.CrtYd")
		)
		(fp_rect
			(start -2.54 1.27)
			(end 2.54 -1.27)
			(stroke
				(width 0)
				(type default)
			)
			(fill no)
			(layer "F.CrtYd")
		)
		(fp_line
			(start 2.54 1.27)
			(end -2.54 1.27)
			(stroke
				(width 0.1)
				(type default)
			)
			(layer "F.Fab")
		)
		(fp_line
			(start 2.54 -1.27)
			(end 2.54 1.27)
			(stroke
				(width 0.1)
				(type default)
			)
			(layer "F.Fab")
		)
		(fp_line
			(start -2.54 1.27)
			(end -2.54 -1.27)
			(stroke
				(width 0.1)
				(type default)
			)
			(layer "F.Fab")
		)
		(fp_line
			(start -2.54 -1.27)
			(end 2.54 -1.27)
			(stroke
				(width 0.1)
				(type default)
			)
			(layer "F.Fab")
		)
		(fp_text user "2"
			(at 3.473704 0.045466 0)
			(unlocked yes)
			(layer "F.SilkS")
			(effects
				(font
					(size 0.7874 0.5842)
					(thickness 0.1524)
				)
				(justify left)
			)
		)
		(fp_text user "1"
			(at -2.825496 -0.894334 0)
			(unlocked yes)
			(layer "F.SilkS")
			(effects
				(font
					(size 0.7874 0.5842)
					(thickness 0.1524)
				)
				(justify left)
			)
		)
		(fp_text user "2"
			(at 2.457704 -0.233934 0)
			(unlocked yes)
			(layer "B.SilkS")
			(effects
				(font
					(size 0.7874 0.5842)
					(thickness 0.1524)
				)
				(justify left mirror)
			)
		)
		(fp_text user "1"
			(at -2.825496 -0.132334 0)
			(unlocked yes)
			(layer "B.SilkS")
			(effects
				(font
					(size 0.7874 0.5842)
					(thickness 0.1524)
				)
				(justify left mirror)
			)
		)
		(pad "1" thru_hole rect
			(at -1.27 0 180)
			(size 1.6764 1.6764)
			(drill 1.1684)
			(layers "*.Cu" "*.Mask")
			(remove_unused_layers no)
			(net "NODE4_EN")
			(clearance 0)
			(padstack
				(mode front_inner_back)
				(layer "Inner"
					(shape circle)
					(size 1.6764 1.6764)
					(clearance 0)
				)
				(layer "B.Cu"
					(shape rect)
					(size 1.6764 1.6764)
					(clearance 0)
				)
			)
		)
		(pad "2" thru_hole circle
			(at 1.27 0 180)
			(size 1.6764 1.6764)
			(drill 1.1684)
			(layers "*.Cu" "*.Mask")
			(remove_unused_layers no)
			(net "N39395053")
			(clearance 0)
		)
	)
	(footprint ""
		(layer "F.Cu")
		(at 144.0942 -3.048 90)
		(property "Reference" "C22"
			(at -2.286 -8.143748 90)
			(unlocked yes)
			(layer "F.SilkS")
			(effects
				(font
					(size 0.7874 0.5842)
					(thickness 0.1524)
				)
				(justify left)
			)
		)
		(property "Value" ""
			(at 0 0 90)
			(layer "F.Fab")
			(effects
				(font
					(size 1.27 1.27)
				)
			)
		)
		(duplicate_pad_numbers_are_jumpers no)
		(fp_line
			(start 0.7874 -0.4064)
			(end 0.7874 0.4064)
			(stroke
				(width 0.1524)
				(type default)
			)
			(layer "F.SilkS")
		)
		(fp_line
			(start -0.7874 -0.4064)
			(end 0.7874 -0.4064)
			(stroke
				(width 0.1524)
				(type default)
			)
			(layer "F.SilkS")
		)
		(fp_line
			(start 0 0.381)
			(end 0 -0.381)
			(stroke
				(width 0.1524)
				(type default)
			)
			(layer "F.SilkS")
		)
		(fp_line
			(start 0.7874 0.4064)
			(end -0.7874 0.4064)
			(stroke
				(width 0.1524)
				(type default)
			)
			(layer "F.SilkS")
		)
		(fp_line
			(start -0.7874 0.4064)
			(end -0.7874 -0.4064)
			(stroke
				(width 0.1524)
				(type default)
			)
			(layer "F.SilkS")
		)
		(fp_poly
			(pts
				(xy -0.5334 0.254) (xy -0.635 0.254) (xy -0.635 0.2286) (xy -0.635 -0.254) (xy -0.5334 -0.254) (xy -0.5334 -0.2794)
				(xy 0.5334 -0.2794) (xy 0.5334 -0.254) (xy 0.635 -0.254) (xy 0.635 0.254) (xy 0.5334 0.254) (xy 0.5334 0.2794)
				(xy -0.508 0.2794) (xy -0.5334 0.2794)
			)
			(stroke
				(width 0)
				(type default)
			)
			(fill no)
			(layer "F.CrtYd")
		)
		(pad "1" smd rect
			(at 0.40005 0 90)
			(size 0.4572 0.508)
			(layers "F.Cu" "F.Mask" "F.Paste")
			(net "P3V3_10G_1_VCCR")
		)
		(pad "2" smd rect
			(at -0.40005 0 90)
			(size 0.4572 0.508)
			(layers "F.Cu" "F.Mask" "F.Paste")
			(net "GND")
		)
	)
	(footprint ""
		(layer "F.Cu")
		(at 27.167332 -16.383 90)
		(property "Reference" "R91"
			(at -3.7846 -0.117348 90)
			(unlocked yes)
			(layer "F.SilkS")
			(effects
				(font
					(size 0.7874 0.5842)
					(thickness 0.1524)
				)
				(justify left)
			)
		)
		(property "Value" ""
			(at 0 0 90)
			(layer "F.Fab")
			(effects
				(font
					(size 1.27 1.27)
				)
			)
		)
		(duplicate_pad_numbers_are_jumpers no)
		(fp_line
			(start 0.7874 -0.4064)
			(end 0.7874 0.4064)
			(stroke
				(width 0.1524)
				(type default)
			)
			(layer "F.SilkS")
		)
		(fp_line
			(start -0.7874 -0.4064)
			(end 0.7874 -0.4064)
			(stroke
				(width 0.1524)
				(type default)
			)
			(layer "F.SilkS")
		)
		(fp_line
			(start 0.7874 0.4064)
			(end -0.7874 0.4064)
			(stroke
				(width 0.1524)
				(type default)
			)
			(layer "F.SilkS")
		)
		(fp_line
			(start -0.7874 0.4064)
			(end -0.7874 -0.4064)
			(stroke
				(width 0.1524)
				(type default)
			)
			(layer "F.SilkS")
		)
		(fp_poly
			(pts
				(xy -0.508 0.2794) (xy -0.508 0.2286) (xy -0.635 0.2286) (xy -0.635 -0.254) (xy -0.5334 -0.254)
				(xy -0.5334 -0.2794) (xy 0.5334 -0.2794) (xy 0.5334 -0.254) (xy 0.635 -0.254) (xy 0.635 0.254) (xy 0.5334 0.254)
				(xy 0.5334 0.2794)
			)
			(stroke
				(width 0)
				(type default)
			)
			(fill no)
			(layer "F.CrtYd")
		)
		(pad "1" smd rect
			(at 0.40005 0 90)
			(size 0.4572 0.508)
			(layers "F.Cu" "F.Mask" "F.Paste")
			(net "N39398095")
		)
		(pad "2" smd rect
			(at -0.40005 0 90)
			(size 0.4572 0.508)
			(layers "F.Cu" "F.Mask" "F.Paste")
			(net "GND")
		)
	)
	(footprint ""
		(layer "F.Cu")
		(at 89.515696 -23.621746 -90)
		(property "Reference" "C1"
			(at -1.168908 5.040122 90)
			(unlocked yes)
			(layer "F.SilkS")
			(effects
				(font
					(size 0.7874 0.5842)
					(thickness 0.1524)
				)
			)
		)
		(property "Value" ""
			(at 0 0 270)
			(layer "F.Fab")
			(effects
				(font
					(size 1.27 1.27)
				)
			)
		)
		(duplicate_pad_numbers_are_jumpers no)
		(fp_line
			(start -1.2954 0.5842)
			(end -1.2954 -0.5842)
			(stroke
				(width 0.1524)
				(type default)
			)
			(layer "F.SilkS")
		)
		(fp_line
			(start 1.2954 0.5842)
			(end -1.2954 0.5842)
			(stroke
				(width 0.1524)
				(type default)
			)
			(layer "F.SilkS")
		)
		(fp_line
			(start -1.2954 -0.5842)
			(end 1.2954 -0.5842)
			(stroke
				(width 0.1524)
				(type default)
			)
			(layer "F.SilkS")
		)
		(fp_line
			(start 0 -0.5842)
			(end 0 0.5842)
			(stroke
				(width 0.1524)
				(type default)
			)
			(layer "F.SilkS")
		)
		(fp_line
			(start 1.2954 -0.5842)
			(end 1.2954 0.5842)
			(stroke
				(width 0.1524)
				(type default)
			)
			(layer "F.SilkS")
		)
		(fp_poly
			(pts
				(xy 0.8636 -0.4572) (xy 0.8636 -0.3556) (xy 1.143 -0.3556) (xy 1.143 0.3556) (xy 0.8636 0.3556)
				(xy 0.8636 0.4572) (xy -0.8636 0.4572) (xy -0.8636 0.3556) (xy -1.143 0.3556) (xy -1.143 -0.3556)
				(xy -0.8636 -0.3556) (xy -0.8636 -0.4572)
			)
			(stroke
				(width 0)
				(type default)
			)
			(fill no)
			(layer "F.CrtYd")
		)
		(fp_line
			(start -0.884936 0.504952)
			(end -0.884936 -0.504952)
			(stroke
				(width 0.1)
				(type default)
			)
			(layer "F.Fab")
		)
		(fp_line
			(start 0.884936 0.504952)
			(end -0.884936 0.504952)
			(stroke
				(width 0.1)
				(type default)
			)
			(layer "F.Fab")
		)
		(fp_line
			(start -0.884936 -0.504952)
			(end 0.884936 -0.504952)
			(stroke
				(width 0.1)
				(type default)
			)
			(layer "F.Fab")
		)
		(fp_line
			(start 0.884936 -0.504952)
			(end 0.884936 0.504952)
			(stroke
				(width 0.1)
				(type default)
			)
			(layer "F.Fab")
		)
		(pad "1" smd rect
			(at 0.7366 0)
			(size 0.7112 0.8128)
			(layers "F.Cu" "F.Mask" "F.Paste")
			(net "P12V")
		)
		(pad "2" smd rect
			(at -0.7366 0)
			(size 0.7112 0.8128)
			(layers "F.Cu" "F.Mask" "F.Paste")
			(net "GND")
		)
	)
)
